FILE_TYPE = MACRO_DRAWING;
SET COLOR_WIRE YELLOW;
SET COLOR_PROP MONO;
SET COLOR_DOT WHITE;
SET COLOR_ARC YELLOW;
SET COLOR_BODY GREEN;
SET COLOR_NOTE MONO;
SET PROP_DISPLAY VALUE;
SET PAGE_NUMBER P180;
FORCEADD INTEL_CORP_BPAGE..1
(4250 200);
FORCEPROP 1 LAST CDS_CON_LAST_MODIFIED Fri Jun 16 17:49:07 2017
J 0
(2825 525);
PAINT ORANGE (2825 525);
DISPLAY INVISIBLE (2825 525);
FORCEPROP 1 LAST CUSTOM_TXT_CDS <CURRENT_DESIGN_SHEET> OF <TOTAL_DESIGN_SHEETS>
J 0
(3750 225);
PAINT ORANGE (3750 225);
FORCEPROP 1 LAST CUSTOM_TXT_CDS <CON_LAST_MODIFIED>
J 0
(250 300);
PAINT ORANGE (250 300);
FORCEPROP 2 LAST CUSTOM_TXT_CDS <XR_PAGE_TITLE>
J 0
(-3640 5450);
DISPLAY 0.638298 (-3640 5450);
PAINT PINK (-3640 5450);
DISPLAY INVISIBLE (-3640 5450);
FORCEPROP 1 LAST SCH_TITLE SPARE
J 0
(-3700 250);
DISPLAY 1.212766 (-3700 250);
PAINT YELLOW (-3700 250);
FORCEPROP 2 LAST CDS_LIB mstr_symbols
J 0
(4250 200);
PAINT MONO (4250 200);
DISPLAY INVISIBLE (4250 200);
FORCEPROP 2 LAST PAGE_BORDER TRUE
J 0
(-3640 5450);
DISPLAY 0.638298 (-3640 5450);
PAINT PINK (-3640 5450);
DISPLAY INVISIBLE (-3640 5450);
FORCEPROP 1 LAST COMMENT_BODY TRUE
J 0
(4262 212);
DISPLAY 0.468085 (4262 212);
PAINT PEACH (4262 212);
DISPLAY INVISIBLE (4262 212);
FORCEPROP 2 LAST CDS_XR_PAGE_TITLE CR-180 : @BASEBOARD_FAB2_LIB.BASEBOARD_FAB2(SCH_1):PAGE180
J 0
(-3640 5450);
DISPLAY 0.638298 (-3640 5450);
PAINT PINK (-3640 5450);
DISPLAY INVISIBLE (-3640 5450);
QUIT
